(kicad_pcb
	(version 20241229)
	(generator "pcbnew")
	(generator_version "9.0")
	(general
		(thickness 1.63)
		(legacy_teardrops no)
	)
	(paper "A4")
	(title_block
		(title "CM4 Baseboard")
		(date "2026-01-05")
		(rev "1.1.1")
		(company "Antmicro Ltd")
		(comment 1 "www.antmicro.com")
		(comment 9 "footprints 143-147 of 506")
	)
	(layers
		(0 "F.Cu" signal)
		(4 "In1.Cu" power)
		(6 "In2.Cu" power)
		(8 "In3.Cu" signal)
		(10 "In4.Cu" signal)
		(2 "B.Cu" signal)
		(9 "F.Adhes" user "F.Adhesive")
		(11 "B.Adhes" user "B.Adhesive")
		(13 "F.Paste" user)
		(15 "B.Paste" user)
		(5 "F.SilkS" user "F.Silkscreen")
		(7 "B.SilkS" user "B.Silkscreen")
		(1 "F.Mask" user)
		(3 "B.Mask" user)
		(17 "Dwgs.User" user "User.Drawings")
		(19 "Cmts.User" user "User.Comments")
		(21 "Eco1.User" user "User.Eco1")
		(23 "Eco2.User" user "User.Eco2")
		(25 "Edge.Cuts" user)
		(27 "Margin" user)
		(31 "F.CrtYd" user "F.Courtyard")
		(29 "B.CrtYd" user "B.Courtyard")
		(35 "F.Fab" user)
		(33 "B.Fab" user)
	)
	(footprint "antmicro-footprints:R_0402_1005Metric"
		(layer "F.Cu")
		(at 137.787962 154.8665)
		(descr "Resistor SMD 0402")
		(tags "resistor SMD 0402")
		(property "Reference" "R606"
			(at 0.98 0.45 0)
			(layer "F.SilkS")
			(effects
				(font
					(size 0.7 0.7)
					(thickness 0.15)
				)
				(justify left bottom)
			)
		)
		(property "Value" "R_1k_0402"
			(at -1.011843 1.772047 0)
			(layer "F.Fab")
			(effects
				(font
					(size 0.7 0.7)
					(thickness 0.15)
				)
				(justify left bottom)
			)
		)
		(property "Datasheet" "https://www.bourns.com/docs/product-datasheets/cr.pdf"
			(at 0 0 0)
			(layer "F.Fab")
			(hide yes)
			(effects
				(font
					(size 1.27 1.27)
					(thickness 0.15)
				)
			)
		)
		(property "MPN" "CR0402-FX-1001GLF"
			(at 0 0 0)
			(unlocked yes)
			(layer "F.Fab")
			(hide yes)
			(effects
				(font
					(size 1 1)
					(thickness 0.15)
				)
			)
		)
		(property "Manufacturer" "Bourns"
			(at 0 0 0)
			(unlocked yes)
			(layer "F.Fab")
			(hide yes)
			(effects
				(font
					(size 1 1)
					(thickness 0.15)
				)
			)
		)
		(property "License" "Apache-2.0"
			(at 0 0 0)
			(unlocked yes)
			(layer "F.Fab")
			(hide yes)
			(effects
				(font
					(size 1 1)
					(thickness 0.15)
				)
			)
		)
		(property "Author" "Antmicro"
			(at 0 0 0)
			(unlocked yes)
			(layer "F.Fab")
			(hide yes)
			(effects
				(font
					(size 1 1)
					(thickness 0.15)
				)
			)
		)
		(property "Val" "1k"
			(at 0 0 0)
			(unlocked yes)
			(layer "F.Fab")
			(hide yes)
			(effects
				(font
					(size 1 1)
					(thickness 0.15)
				)
			)
		)
		(property "Tolerance" "1%"
			(at 0 0 0)
			(unlocked yes)
			(layer "F.Fab")
			(hide yes)
			(effects
				(font
					(size 1 1)
					(thickness 0.15)
				)
			)
		)
		(sheetname "/CSI/")
		(sheetfile "csi.kicad_sch")
		(attr smd)
		(fp_rect
			(start -0.925 -0.47)
			(end 0.925 0.47)
			(stroke
				(width 0.05)
				(type default)
			)
			(fill no)
			(layer "F.CrtYd")
		)
		(fp_rect
			(start -0.5 -0.25)
			(end 0.5 0.25)
			(stroke
				(width 0.15)
				(type solid)
			)
			(fill no)
			(layer "F.Fab")
		)
		(fp_text user "${REFERENCE}"
			(at -0.95 3.168 0)
			(layer "F.Fab")
			(effects
				(font
					(size 0.7 0.7)
					(thickness 0.15)
				)
				(justify left bottom)
			)
		)
		(fp_text user "License: Apache-2.0"
			(at -0.95 5.169 0)
			(layer "F.Fab")
			(effects
				(font
					(size 0.7 0.7)
					(thickness 0.15)
				)
				(justify left bottom)
			)
		)
		(fp_text user "Author: Antmicro"
			(at -0.95 4.169 0)
			(layer "F.Fab")
			(effects
				(font
					(size 0.7 0.7)
					(thickness 0.15)
				)
				(justify left bottom)
			)
		)
		(pad "1" smd roundrect
			(at -0.48 0)
			(size 0.59 0.64)
			(layers "F.Cu" "F.Mask" "F.Paste")
			(roundrect_rratio 0.25)
			(net 479 "Net-(D601-A)")
			(pintype "passive")
		)
		(pad "2" smd roundrect
			(at 0.48 0)
			(size 0.59 0.64)
			(layers "F.Cu" "F.Mask" "F.Paste")
			(roundrect_rratio 0.25)
			(net 20 "/CSI/CSI_5V")
			(pintype "passive")
		)
	)
	(footprint "antmicro-footprints:C_0402_1005Metric"
		(layer "F.Cu")
		(at 66.142962 172.7165 180)
		(descr "Capacitor SMD 0402")
		(tags "capacitor SMD 0402")
		(property "Reference" "C807"
			(at 0.892962 -0.0335 0)
			(layer "F.SilkS")
			(effects
				(font
					(size 0.7 0.7)
					(thickness 0.15)
				)
				(justify right bottom)
			)
		)
		(property "Value" "C_2u2_0402"
			(at -1.022927 2.155213 0)
			(layer "F.Fab")
			(effects
				(font
					(size 0.7 0.7)
					(thickness 0.15)
				)
				(justify right bottom)
			)
		)
		(property "Datasheet" "https://product.tdk.com/en/search/capacitor/ceramic/mlcc/info?part_no=C1005X5R1A225K050BC"
			(at 0 0 180)
			(layer "F.Fab")
			(hide yes)
			(effects
				(font
					(size 1.27 1.27)
					(thickness 0.15)
				)
			)
		)
		(property "MPN" "C1005X5R1A225K050BC"
			(at 0 0 180)
			(unlocked yes)
			(layer "F.Fab")
			(hide yes)
			(effects
				(font
					(size 1 1)
					(thickness 0.15)
				)
			)
		)
		(property "Manufacturer" "TDK"
			(at 0 0 180)
			(unlocked yes)
			(layer "F.Fab")
			(hide yes)
			(effects
				(font
					(size 1 1)
					(thickness 0.15)
				)
			)
		)
		(property "License" "Apache-2.0"
			(at 0 0 180)
			(unlocked yes)
			(layer "F.Fab")
			(hide yes)
			(effects
				(font
					(size 1 1)
					(thickness 0.15)
				)
			)
		)
		(property "Author" "Antmicro"
			(at 0 0 180)
			(unlocked yes)
			(layer "F.Fab")
			(hide yes)
			(effects
				(font
					(size 1 1)
					(thickness 0.15)
				)
			)
		)
		(property "Val" "2u2"
			(at 0 0 180)
			(unlocked yes)
			(layer "F.Fab")
			(hide yes)
			(effects
				(font
					(size 1 1)
					(thickness 0.15)
				)
			)
		)
		(property "Voltage" ""
			(at 0 0 180)
			(unlocked yes)
			(layer "F.Fab")
			(hide yes)
			(effects
				(font
					(size 1 1)
					(thickness 0.15)
				)
			)
		)
		(property "Dielectric" ""
			(at 0 0 180)
			(unlocked yes)
			(layer "F.Fab")
			(hide yes)
			(effects
				(font
					(size 1 1)
					(thickness 0.15)
				)
			)
		)
		(sheetname "/Peripherals/")
		(sheetfile "peripherals.kicad_sch")
		(attr smd)
		(fp_rect
			(start -0.925 -0.47)
			(end 0.925 0.47)
			(stroke
				(width 0.05)
				(type default)
			)
			(fill no)
			(layer "F.CrtYd")
		)
		(fp_line
			(start 0.504 0.248)
			(end -0.494 0.248)
			(stroke
				(width 0.15)
				(type solid)
			)
			(layer "F.Fab")
		)
		(fp_line
			(start 0.504 -0.25)
			(end 0.504 0.248)
			(stroke
				(width 0.15)
				(type solid)
			)
			(layer "F.Fab")
		)
		(fp_line
			(start -0.494 0.248)
			(end -0.494 -0.25)
			(stroke
				(width 0.15)
				(type solid)
			)
			(layer "F.Fab")
		)
		(fp_line
			(start -0.494 -0.25)
			(end 0.504 -0.25)
			(stroke
				(width 0.15)
				(type solid)
			)
			(layer "F.Fab")
		)
		(fp_text user "License: Apache-2.0"
			(at -0.939 5.799 180)
			(layer "F.Fab")
			(effects
				(font
					(size 0.7 0.7)
					(thickness 0.15)
				)
				(justify left bottom)
			)
		)
		(fp_text user "${REFERENCE}"
			(at -0.939 4.599 180)
			(layer "F.Fab")
			(effects
				(font
					(size 0.7 0.7)
					(thickness 0.15)
				)
				(justify left bottom)
			)
		)
		(fp_text user "Author: Antmicro"
			(at -0.939 3.399 180)
			(layer "F.Fab")
			(effects
				(font
					(size 0.7 0.7)
					(thickness 0.15)
				)
				(justify left bottom)
			)
		)
		(pad "1" smd roundrect
			(at -0.48 0 180)
			(size 0.59 0.64)
			(layers "F.Cu" "F.Mask" "F.Paste")
			(roundrect_rratio 0.25)
			(net 94 "Net-(U801-TVDD_IN)")
			(pintype "passive")
		)
		(pad "2" smd roundrect
			(at 0.48 0 180)
			(size 0.59 0.64)
			(layers "F.Cu" "F.Mask" "F.Paste")
			(roundrect_rratio 0.25)
			(net 3 "GND")
			(pintype "passive")
		)
	)
	(footprint "antmicro-footprints:R_0402_1005Metric"
		(layer "F.Cu")
		(at 68.292962 143.9065 180)
		(descr "Resistor SMD 0402")
		(tags "resistor SMD 0402")
		(property "Reference" "R2"
			(at -0.45 0.565 0)
			(layer "F.SilkS")
			(effects
				(font
					(size 0.7 0.7)
					(thickness 0.15)
				)
				(justify right bottom)
			)
		)
		(property "Value" "R_0R_0402"
			(at -1.011843 1.772047 0)
			(layer "F.Fab")
			(effects
				(font
					(size 0.7 0.7)
					(thickness 0.15)
				)
				(justify right bottom)
			)
		)
		(property "Datasheet" "https://industrial.panasonic.com/cdbs/www-data/pdf/RDA0000/AOA0000C301.pdf"
			(at 0 0 180)
			(layer "F.Fab")
			(hide yes)
			(effects
				(font
					(size 1.27 1.27)
					(thickness 0.15)
				)
			)
		)
		(property "Manufacturer" "Panasonic"
			(at 0 0 180)
			(unlocked yes)
			(layer "F.Fab")
			(hide yes)
			(effects
				(font
					(size 1 1)
					(thickness 0.15)
				)
			)
		)
		(property "MPN" "ERJ2GE0R00X"
			(at 0 0 180)
			(unlocked yes)
			(layer "F.Fab")
			(hide yes)
			(effects
				(font
					(size 1 1)
					(thickness 0.15)
				)
			)
		)
		(property "Val" "0R"
			(at 0 0 180)
			(unlocked yes)
			(layer "F.Fab")
			(hide yes)
			(effects
				(font
					(size 1 1)
					(thickness 0.15)
				)
			)
		)
		(property "License" "Apache-2.0"
			(at 0 0 180)
			(unlocked yes)
			(layer "F.Fab")
			(hide yes)
			(effects
				(font
					(size 1 1)
					(thickness 0.15)
				)
			)
		)
		(property "Author" "Antmicro"
			(at 0 0 180)
			(unlocked yes)
			(layer "F.Fab")
			(hide yes)
			(effects
				(font
					(size 1 1)
					(thickness 0.15)
				)
			)
		)
		(property "Tolerance" "~"
			(at 0 0 180)
			(unlocked yes)
			(layer "F.Fab")
			(hide yes)
			(effects
				(font
					(size 1 1)
					(thickness 0.15)
				)
			)
		)
		(property "Current" "1A"
			(at 0 0 180)
			(unlocked yes)
			(layer "F.Fab")
			(hide yes)
			(effects
				(font
					(size 1 1)
					(thickness 0.15)
				)
			)
		)
		(sheetname "/Compute module/")
		(sheetfile "compute-module.kicad_sch")
		(attr smd)
		(fp_rect
			(start -0.925 -0.47)
			(end 0.925 0.47)
			(stroke
				(width 0.05)
				(type default)
			)
			(fill no)
			(layer "F.CrtYd")
		)
		(fp_rect
			(start -0.5 -0.25)
			(end 0.5 0.25)
			(stroke
				(width 0.15)
				(type solid)
			)
			(fill no)
			(layer "F.Fab")
		)
		(fp_text user "Author: Antmicro"
			(at -0.95 4.169 180)
			(layer "F.Fab")
			(effects
				(font
					(size 0.7 0.7)
					(thickness 0.15)
				)
				(justify left bottom)
			)
		)
		(fp_text user "License: Apache-2.0"
			(at -0.95 5.169 180)
			(layer "F.Fab")
			(effects
				(font
					(size 0.7 0.7)
					(thickness 0.15)
				)
				(justify left bottom)
			)
		)
		(fp_text user "${REFERENCE}"
			(at -0.95 3.168 180)
			(layer "F.Fab")
			(effects
				(font
					(size 0.7 0.7)
					(thickness 0.15)
				)
				(justify left bottom)
			)
		)
		(pad "1" smd roundrect
			(at -0.48 0 180)
			(size 0.59 0.64)
			(layers "F.Cu" "F.Mask" "F.Paste")
			(roundrect_rratio 0.25)
			(net 252 "/Compute module/~{PWR_LED}")
			(pintype "passive")
		)
		(pad "2" smd roundrect
			(at 0.48 0 180)
			(size 0.59 0.64)
			(layers "F.Cu" "F.Mask" "F.Paste")
			(roundrect_rratio 0.25)
			(net 491 "Net-(Q206-G)")
			(pintype "passive")
		)
	)
	(footprint "antmicro-footprints:R_0402_1005Metric"
		(layer "F.Cu")
		(at 133.767962 121.1915 -90)
		(descr "Resistor SMD 0402")
		(tags "resistor SMD 0402")
		(property "Reference" "R801"
			(at 6.895 -0.53 90)
			(layer "F.SilkS")
			(effects
				(font
					(size 0.7 0.7)
					(thickness 0.15)
				)
				(justify right bottom)
			)
		)
		(property "Value" "R_0R_0402"
			(at -1.011843 1.772047 90)
			(layer "F.Fab")
			(effects
				(font
					(size 0.7 0.7)
					(thickness 0.15)
				)
				(justify right bottom)
			)
		)
		(property "Datasheet" "https://industrial.panasonic.com/cdbs/www-data/pdf/RDA0000/AOA0000C301.pdf"
			(at 0 0 270)
			(layer "F.Fab")
			(hide yes)
			(effects
				(font
					(size 1.27 1.27)
					(thickness 0.15)
				)
			)
		)
		(property "MPN" "ERJ2GE0R00X"
			(at 0 0 270)
			(unlocked yes)
			(layer "F.Fab")
			(hide yes)
			(effects
				(font
					(size 1 1)
					(thickness 0.15)
				)
			)
		)
		(property "Manufacturer" "Panasonic"
			(at 0 0 270)
			(unlocked yes)
			(layer "F.Fab")
			(hide yes)
			(effects
				(font
					(size 1 1)
					(thickness 0.15)
				)
			)
		)
		(property "License" "Apache-2.0"
			(at 0 0 270)
			(unlocked yes)
			(layer "F.Fab")
			(hide yes)
			(effects
				(font
					(size 1 1)
					(thickness 0.15)
				)
			)
		)
		(property "Author" "Antmicro"
			(at 0 0 270)
			(unlocked yes)
			(layer "F.Fab")
			(hide yes)
			(effects
				(font
					(size 1 1)
					(thickness 0.15)
				)
			)
		)
		(property "Val" "0R"
			(at 0 0 270)
			(unlocked yes)
			(layer "F.Fab")
			(hide yes)
			(effects
				(font
					(size 1 1)
					(thickness 0.15)
				)
			)
		)
		(property "Tolerance" "~"
			(at 0 0 270)
			(unlocked yes)
			(layer "F.Fab")
			(hide yes)
			(effects
				(font
					(size 1 1)
					(thickness 0.15)
				)
			)
		)
		(property "Current" "1A"
			(at 0 0 270)
			(unlocked yes)
			(layer "F.Fab")
			(hide yes)
			(effects
				(font
					(size 1 1)
					(thickness 0.15)
				)
			)
		)
		(sheetname "/Peripherals/")
		(sheetfile "peripherals.kicad_sch")
		(attr smd exclude_from_pos_files exclude_from_bom dnp)
		(fp_rect
			(start -0.925 -0.47)
			(end 0.925 0.47)
			(stroke
				(width 0.05)
				(type default)
			)
			(fill no)
			(layer "F.CrtYd")
		)
		(fp_rect
			(start -0.5 -0.25)
			(end 0.5 0.25)
			(stroke
				(width 0.15)
				(type solid)
			)
			(fill no)
			(layer "F.Fab")
		)
		(fp_text user "Author: Antmicro"
			(at -0.95 4.169 270)
			(layer "F.Fab")
			(effects
				(font
					(size 0.7 0.7)
					(thickness 0.15)
				)
				(justify left bottom)
			)
		)
		(fp_text user "${REFERENCE}"
			(at -0.95 3.168 270)
			(layer "F.Fab")
			(effects
				(font
					(size 0.7 0.7)
					(thickness 0.15)
				)
				(justify left bottom)
			)
		)
		(fp_text user "License: Apache-2.0"
			(at -0.95 5.169 270)
			(layer "F.Fab")
			(effects
				(font
					(size 0.7 0.7)
					(thickness 0.15)
				)
				(justify left bottom)
			)
		)
		(pad "1" smd roundrect
			(at -0.48 0 270)
			(size 0.59 0.64)
			(layers "F.Cu" "F.Mask" "F.Paste")
			(roundrect_rratio 0.25)
			(net 317 "/Peripherals/VLED")
			(pintype "passive")
		)
		(pad "2" smd roundrect
			(at 0.48 0 270)
			(size 0.59 0.64)
			(layers "F.Cu" "F.Mask" "F.Paste")
			(roundrect_rratio 0.25)
			(net 10 "+5V")
			(pintype "passive")
		)
	)
	(footprint "antmicro-footprints:R_0402_1005Metric"
		(layer "F.Cu")
		(at 54.827962 130.8765)
		(descr "Resistor SMD 0402")
		(tags "resistor SMD 0402")
		(property "Reference" "R407"
			(at -1.49 -5.38 0)
			(layer "F.SilkS")
			(effects
				(font
					(size 0.7 0.7)
					(thickness 0.15)
				)
				(justify left bottom)
			)
		)
		(property "Value" "R_10k_0402"
			(at -1.011843 1.772047 0)
			(layer "F.Fab")
			(effects
				(font
					(size 0.7 0.7)
					(thickness 0.15)
				)
				(justify left bottom)
			)
		)
		(property "Datasheet" "https://www.bourns.com/docs/product-datasheets/cr.pdf"
			(at 0 0 0)
			(layer "F.Fab")
			(hide yes)
			(effects
				(font
					(size 1.27 1.27)
					(thickness 0.15)
				)
			)
		)
		(property "Manufacturer" "Bourns"
			(at 0 0 0)
			(unlocked yes)
			(layer "F.Fab")
			(hide yes)
			(effects
				(font
					(size 1 1)
					(thickness 0.15)
				)
			)
		)
		(property "MPN" "CR0402-FX-1002GLF"
			(at 0 0 0)
			(unlocked yes)
			(layer "F.Fab")
			(hide yes)
			(effects
				(font
					(size 1 1)
					(thickness 0.15)
				)
			)
		)
		(property "Val" "10k"
			(at 0 0 0)
			(unlocked yes)
			(layer "F.Fab")
			(hide yes)
			(effects
				(font
					(size 1 1)
					(thickness 0.15)
				)
			)
		)
		(property "License" "Apache-2.0"
			(at 0 0 0)
			(unlocked yes)
			(layer "F.Fab")
			(hide yes)
			(effects
				(font
					(size 1 1)
					(thickness 0.15)
				)
			)
		)
		(property "Author" "Antmicro"
			(at 0 0 0)
			(unlocked yes)
			(layer "F.Fab")
			(hide yes)
			(effects
				(font
					(size 1 1)
					(thickness 0.15)
				)
			)
		)
		(property "Tolerance" "1%"
			(at 0 0 0)
			(unlocked yes)
			(layer "F.Fab")
			(hide yes)
			(effects
				(font
					(size 1 1)
					(thickness 0.15)
				)
			)
		)
		(sheetname "/Ethernet/")
		(sheetfile "ethernet.kicad_sch")
		(attr smd exclude_from_pos_files exclude_from_bom dnp)
		(fp_rect
			(start -0.925 -0.47)
			(end 0.925 0.47)
			(stroke
				(width 0.05)
				(type default)
			)
			(fill no)
			(layer "F.CrtYd")
		)
		(fp_rect
			(start -0.5 -0.25)
			(end 0.5 0.25)
			(stroke
				(width 0.15)
				(type solid)
			)
			(fill no)
			(layer "F.Fab")
		)
		(fp_text user "${REFERENCE}"
			(at -0.95 3.168 0)
			(layer "F.Fab")
			(effects
				(font
					(size 0.7 0.7)
					(thickness 0.15)
				)
				(justify left bottom)
			)
		)
		(fp_text user "Author: Antmicro"
			(at -0.95 4.169 0)
			(layer "F.Fab")
			(effects
				(font
					(size 0.7 0.7)
					(thickness 0.15)
				)
				(justify left bottom)
			)
		)
		(fp_text user "License: Apache-2.0"
			(at -0.95 5.169 0)
			(layer "F.Fab")
			(effects
				(font
					(size 0.7 0.7)
					(thickness 0.15)
				)
				(justify left bottom)
			)
		)
		(pad "1" smd roundrect
			(at -0.48 0)
			(size 0.59 0.64)
			(layers "F.Cu" "F.Mask" "F.Paste")
			(roundrect_rratio 0.25)
			(net 362 "/Ethernet/TPH")
			(pintype "passive")
		)
		(pad "2" smd roundrect
			(at 0.48 0)
			(size 0.59 0.64)
			(layers "F.Cu" "F.Mask" "F.Paste")
			(roundrect_rratio 0.25)
			(net 33 "/Ethernet/VDD")
			(pintype "passive")
		)
	)
)
